(kicad_pcb
	(version 20260206)
	(generator "pcbnew")
	(generator_version "10.0")
	(general
		(thickness 1.6)
		(legacy_teardrops no)
	)
	(paper "A4")
	(title_block
		(title "04192023_DAF0TMB3IC0_F0TG_MB_C_brd_V02_OCP.brd")
		(comment 1 "Grand Teton / footprints 4428-4435 of 8354")
	)
	(layers
		(0 "F.Cu" signal "TOP")
		(4 "In1.Cu" signal "GND")
		(6 "In2.Cu" signal "IN1")
		(8 "In3.Cu" signal "GND1")
		(10 "In4.Cu" signal "IN2")
		(12 "In5.Cu" signal "GND2")
		(14 "In6.Cu" signal "IN3")
		(16 "In7.Cu" signal "GND3")
		(18 "In8.Cu" signal "VCC")
		(20 "In9.Cu" signal "VCC1")
		(22 "In10.Cu" signal "GND4")
		(24 "In11.Cu" signal "IN4")
		(26 "In12.Cu" signal "GND5")
		(28 "In13.Cu" signal "IN5")
		(30 "In14.Cu" signal "GND6")
		(32 "In15.Cu" signal "IN6")
		(34 "In16.Cu" signal "GND7")
		(2 "B.Cu" signal "BOTTOM")
		(9 "F.Adhes" user "F.Adhesive")
		(11 "B.Adhes" user "B.Adhesive")
		(13 "F.Paste" user "Package Geometry/Pastemask Top")
		(15 "B.Paste" user "Package Geometry/Pastemask Bottom")
		(5 "F.SilkS" user "Ref Des/Silkscreen Top")
		(7 "B.SilkS" user "Ref Des/Silkscreen Bottom")
		(1 "F.Mask" user "Board Geometry/Soldermask Top")
		(3 "B.Mask" user "Board Geometry/Soldermask Bottom")
		(17 "Dwgs.User" user "User.Drawings")
		(19 "Cmts.User" user "User.Comments")
		(21 "Eco1.User" user "User.Eco1")
		(23 "Eco2.User" user "User.Eco2")
		(25 "Edge.Cuts" user "Board Geometry/Outline")
		(27 "Margin" user)
		(31 "F.CrtYd" user "Package Geometry/Place Bound Top")
		(29 "B.CrtYd" user "Package Geometry/Place Bound Bottom")
		(35 "F.Fab" user "Ref Des/Assembly Top")
		(33 "B.Fab" user "Ref Des/Assembly Bottom")
	)
	(footprint ""
		(layer "F.Cu")
		(at 171.20743 -103.96728)
		(property "Reference" "R12"
			(at 0 0 0)
			(layer "F.SilkS")
			(hide yes)
			(effects
				(font
					(size 1.27 1.27)
				)
			)
		)
		(property "Value" ""
			(at 0 0 0)
			(layer "F.Fab")
			(effects
				(font
					(size 1.27 1.27)
				)
			)
		)
		(duplicate_pad_numbers_are_jumpers no)
		(fp_line
			(start -0.7874 -0.4064)
			(end 0.7874 -0.4064)
			(stroke
				(width 0.1524)
				(type default)
			)
			(layer "F.SilkS")
		)
		(fp_line
			(start -0.7874 0.4064)
			(end -0.7874 -0.4064)
			(stroke
				(width 0.1524)
				(type default)
			)
			(layer "F.SilkS")
		)
		(fp_line
			(start 0.7874 -0.4064)
			(end 0.7874 0.4064)
			(stroke
				(width 0.1524)
				(type default)
			)
			(layer "F.SilkS")
		)
		(fp_line
			(start 0.7874 0.4064)
			(end -0.7874 0.4064)
			(stroke
				(width 0.1524)
				(type default)
			)
			(layer "F.SilkS")
		)
		(fp_line
			(start -0.67945 -0.305054)
			(end -0.12065 -0.305054)
			(stroke
				(width 0.1)
				(type default)
			)
			(layer "F.Fab")
		)
		(fp_line
			(start -0.67945 0.3048)
			(end -0.67945 -0.305054)
			(stroke
				(width 0.1)
				(type default)
			)
			(layer "F.Fab")
		)
		(fp_line
			(start -0.12065 -0.305054)
			(end -0.12065 -0.2794)
			(stroke
				(width 0.1)
				(type default)
			)
			(layer "F.Fab")
		)
		(fp_line
			(start -0.12065 -0.2794)
			(end 0.12065 -0.2794)
			(stroke
				(width 0.1)
				(type default)
			)
			(layer "F.Fab")
		)
		(fp_line
			(start -0.12065 0.2794)
			(end -0.12065 0.3048)
			(stroke
				(width 0.1)
				(type default)
			)
			(layer "F.Fab")
		)
		(fp_line
			(start -0.12065 0.3048)
			(end -0.67945 0.3048)
			(stroke
				(width 0.1)
				(type default)
			)
			(layer "F.Fab")
		)
		(fp_line
			(start 0.120396 0.2794)
			(end -0.12065 0.2794)
			(stroke
				(width 0.1)
				(type default)
			)
			(layer "F.Fab")
		)
		(fp_line
			(start 0.120396 0.3048)
			(end 0.120396 0.2794)
			(stroke
				(width 0.1)
				(type default)
			)
			(layer "F.Fab")
		)
		(fp_line
			(start 0.12065 -0.3048)
			(end 0.67945 -0.3048)
			(stroke
				(width 0.1)
				(type default)
			)
			(layer "F.Fab")
		)
		(fp_line
			(start 0.12065 -0.2794)
			(end 0.12065 -0.3048)
			(stroke
				(width 0.1)
				(type default)
			)
			(layer "F.Fab")
		)
		(fp_line
			(start 0.67945 -0.3048)
			(end 0.67945 0.3048)
			(stroke
				(width 0.1)
				(type default)
			)
			(layer "F.Fab")
		)
		(fp_line
			(start 0.67945 0.3048)
			(end 0.120396 0.3048)
			(stroke
				(width 0.1)
				(type default)
			)
			(layer "F.Fab")
		)
		(pad "1" smd circle
			(at -0.40005 0)
			(size 0 0)
			(layers "F.Cu" "F.Mask" "F.Paste")
			(net "FM_I3C_CPU1_MUX0_OE_N")
		)
		(pad "2" smd circle
			(at 0.40005 0)
			(size 0 0)
			(layers "F.Cu" "F.Mask" "F.Paste")
			(net "GND")
		)
	)
	(footprint ""
		(layer "F.Cu")
		(at 292.655244 -397.884396 -90)
		(property "Reference" "R1218"
			(at 0 0 270)
			(layer "F.SilkS")
			(hide yes)
			(effects
				(font
					(size 1.27 1.27)
				)
			)
		)
		(property "Value" ""
			(at 0 0 270)
			(layer "F.Fab")
			(effects
				(font
					(size 1.27 1.27)
				)
			)
		)
		(duplicate_pad_numbers_are_jumpers no)
		(fp_line
			(start -0.32512 0.175006)
			(end -0.32512 -0.175006)
			(stroke
				(width 0.1)
				(type default)
			)
			(layer "F.Fab")
		)
		(fp_line
			(start 0.32512 0.175006)
			(end -0.32512 0.175006)
			(stroke
				(width 0.1)
				(type default)
			)
			(layer "F.Fab")
		)
		(fp_line
			(start -0.32512 -0.175006)
			(end 0.32512 -0.175006)
			(stroke
				(width 0.1)
				(type default)
			)
			(layer "F.Fab")
		)
		(fp_line
			(start 0.32512 -0.175006)
			(end 0.32512 0.175006)
			(stroke
				(width 0.1)
				(type default)
			)
			(layer "F.Fab")
		)
		(pad "1" smd rect
			(at -0.2667 0 270)
			(size 0.3048 0.381)
			(layers "F.Cu" "F.Mask" "F.Paste")
			(net "GND")
		)
		(pad "2" smd rect
			(at 0.2667 0 90)
			(size 0.3048 0.381)
			(layers "F.Cu" "F.Mask" "F.Paste")
			(net "RT_ROM_MUX6_OE_N")
		)
	)
	(footprint ""
		(layer "F.Cu")
		(at 102.563422 -39.886636 180)
		(property "Reference" "R3182"
			(at 0 0 180)
			(layer "F.SilkS")
			(hide yes)
			(effects
				(font
					(size 1.27 1.27)
				)
			)
		)
		(property "Value" ""
			(at 0 0 180)
			(layer "F.Fab")
			(effects
				(font
					(size 1.27 1.27)
				)
			)
		)
		(duplicate_pad_numbers_are_jumpers no)
		(fp_line
			(start 0.7874 0.4064)
			(end -0.7874 0.4064)
			(stroke
				(width 0.1524)
				(type default)
			)
			(layer "F.SilkS")
		)
		(fp_line
			(start 0.7874 -0.4064)
			(end 0.7874 0.4064)
			(stroke
				(width 0.1524)
				(type default)
			)
			(layer "F.SilkS")
		)
		(fp_line
			(start -0.7874 0.4064)
			(end -0.7874 -0.4064)
			(stroke
				(width 0.1524)
				(type default)
			)
			(layer "F.SilkS")
		)
		(fp_line
			(start -0.7874 -0.4064)
			(end 0.7874 -0.4064)
			(stroke
				(width 0.1524)
				(type default)
			)
			(layer "F.SilkS")
		)
		(fp_line
			(start 0.67945 0.3048)
			(end 0.120396 0.3048)
			(stroke
				(width 0.1)
				(type default)
			)
			(layer "F.Fab")
		)
		(fp_line
			(start 0.67945 -0.3048)
			(end 0.67945 0.3048)
			(stroke
				(width 0.1)
				(type default)
			)
			(layer "F.Fab")
		)
		(fp_line
			(start 0.12065 -0.2794)
			(end 0.12065 -0.3048)
			(stroke
				(width 0.1)
				(type default)
			)
			(layer "F.Fab")
		)
		(fp_line
			(start 0.12065 -0.3048)
			(end 0.67945 -0.3048)
			(stroke
				(width 0.1)
				(type default)
			)
			(layer "F.Fab")
		)
		(fp_line
			(start 0.120396 0.3048)
			(end 0.120396 0.2794)
			(stroke
				(width 0.1)
				(type default)
			)
			(layer "F.Fab")
		)
		(fp_line
			(start 0.120396 0.2794)
			(end -0.12065 0.2794)
			(stroke
				(width 0.1)
				(type default)
			)
			(layer "F.Fab")
		)
		(fp_line
			(start -0.12065 0.3048)
			(end -0.67945 0.3048)
			(stroke
				(width 0.1)
				(type default)
			)
			(layer "F.Fab")
		)
		(fp_line
			(start -0.12065 0.2794)
			(end -0.12065 0.3048)
			(stroke
				(width 0.1)
				(type default)
			)
			(layer "F.Fab")
		)
		(fp_line
			(start -0.12065 -0.2794)
			(end 0.12065 -0.2794)
			(stroke
				(width 0.1)
				(type default)
			)
			(layer "F.Fab")
		)
		(fp_line
			(start -0.12065 -0.305054)
			(end -0.12065 -0.2794)
			(stroke
				(width 0.1)
				(type default)
			)
			(layer "F.Fab")
		)
		(fp_line
			(start -0.67945 0.3048)
			(end -0.67945 -0.305054)
			(stroke
				(width 0.1)
				(type default)
			)
			(layer "F.Fab")
		)
		(fp_line
			(start -0.67945 -0.305054)
			(end -0.12065 -0.305054)
			(stroke
				(width 0.1)
				(type default)
			)
			(layer "F.Fab")
		)
		(pad "1" smd circle
			(at -0.40005 0 180)
			(size 0 0)
			(layers "F.Cu" "F.Mask" "F.Paste")
			(net "P3V3_OCP_V3_2")
		)
		(pad "2" smd circle
			(at 0.40005 0 180)
			(size 0 0)
			(layers "F.Cu" "F.Mask" "F.Paste")
			(net "IRQ_LVC3_OCP_V3_2_WAKE_N")
		)
	)
	(footprint ""
		(layer "F.Cu")
		(at 297.554142 -397.4084)
		(property "Reference" "R971"
			(at 0 0 0)
			(layer "F.SilkS")
			(hide yes)
			(effects
				(font
					(size 1.27 1.27)
				)
			)
		)
		(property "Value" ""
			(at 0 0 0)
			(layer "F.Fab")
			(effects
				(font
					(size 1.27 1.27)
				)
			)
		)
		(duplicate_pad_numbers_are_jumpers no)
		(fp_line
			(start -0.32512 -0.175006)
			(end 0.32512 -0.175006)
			(stroke
				(width 0.1)
				(type default)
			)
			(layer "F.Fab")
		)
		(fp_line
			(start -0.32512 0.175006)
			(end -0.32512 -0.175006)
			(stroke
				(width 0.1)
				(type default)
			)
			(layer "F.Fab")
		)
		(fp_line
			(start 0.32512 -0.175006)
			(end 0.32512 0.175006)
			(stroke
				(width 0.1)
				(type default)
			)
			(layer "F.Fab")
		)
		(fp_line
			(start 0.32512 0.175006)
			(end -0.32512 0.175006)
			(stroke
				(width 0.1)
				(type default)
			)
			(layer "F.Fab")
		)
		(pad "1" smd rect
			(at -0.2667 0)
			(size 0.3048 0.381)
			(layers "F.Cu" "F.Mask" "F.Paste")
			(net "RST_RT_CPU0_P0_RESET_R_N")
		)
		(pad "2" smd rect
			(at 0.2667 0 180)
			(size 0.3048 0.381)
			(layers "F.Cu" "F.Mask" "F.Paste")
			(net "GND")
		)
	)
	(footprint ""
		(layer "F.Cu")
		(at 257.766312 -66.86931 90)
		(property "Reference" "R4074"
			(at 0 0 90)
			(layer "F.SilkS")
			(hide yes)
			(effects
				(font
					(size 1.27 1.27)
				)
			)
		)
		(property "Value" ""
			(at 0 0 90)
			(layer "F.Fab")
			(effects
				(font
					(size 1.27 1.27)
				)
			)
		)
		(duplicate_pad_numbers_are_jumpers no)
		(fp_line
			(start 0.7874 -0.4064)
			(end 0.7874 0.4064)
			(stroke
				(width 0.1524)
				(type default)
			)
			(layer "F.SilkS")
		)
		(fp_line
			(start -0.7874 -0.4064)
			(end 0.7874 -0.4064)
			(stroke
				(width 0.1524)
				(type default)
			)
			(layer "F.SilkS")
		)
		(fp_line
			(start 0.7874 0.4064)
			(end -0.7874 0.4064)
			(stroke
				(width 0.1524)
				(type default)
			)
			(layer "F.SilkS")
		)
		(fp_line
			(start -0.7874 0.4064)
			(end -0.7874 -0.4064)
			(stroke
				(width 0.1524)
				(type default)
			)
			(layer "F.SilkS")
		)
		(fp_line
			(start -0.12065 -0.305054)
			(end -0.12065 -0.2794)
			(stroke
				(width 0.1)
				(type default)
			)
			(layer "F.Fab")
		)
		(fp_line
			(start -0.67945 -0.305054)
			(end -0.12065 -0.305054)
			(stroke
				(width 0.1)
				(type default)
			)
			(layer "F.Fab")
		)
		(fp_line
			(start 0.67945 -0.3048)
			(end 0.67945 0.3048)
			(stroke
				(width 0.1)
				(type default)
			)
			(layer "F.Fab")
		)
		(fp_line
			(start 0.12065 -0.3048)
			(end 0.67945 -0.3048)
			(stroke
				(width 0.1)
				(type default)
			)
			(layer "F.Fab")
		)
		(fp_line
			(start 0.12065 -0.2794)
			(end 0.12065 -0.3048)
			(stroke
				(width 0.1)
				(type default)
			)
			(layer "F.Fab")
		)
		(fp_line
			(start -0.12065 -0.2794)
			(end 0.12065 -0.2794)
			(stroke
				(width 0.1)
				(type default)
			)
			(layer "F.Fab")
		)
		(fp_line
			(start 0.120396 0.2794)
			(end -0.12065 0.2794)
			(stroke
				(width 0.1)
				(type default)
			)
			(layer "F.Fab")
		)
		(fp_line
			(start -0.12065 0.2794)
			(end -0.12065 0.3048)
			(stroke
				(width 0.1)
				(type default)
			)
			(layer "F.Fab")
		)
		(fp_line
			(start 0.67945 0.3048)
			(end 0.120396 0.3048)
			(stroke
				(width 0.1)
				(type default)
			)
			(layer "F.Fab")
		)
		(fp_line
			(start 0.120396 0.3048)
			(end 0.120396 0.2794)
			(stroke
				(width 0.1)
				(type default)
			)
			(layer "F.Fab")
		)
		(fp_line
			(start -0.12065 0.3048)
			(end -0.67945 0.3048)
			(stroke
				(width 0.1)
				(type default)
			)
			(layer "F.Fab")
		)
		(fp_line
			(start -0.67945 0.3048)
			(end -0.67945 -0.305054)
			(stroke
				(width 0.1)
				(type default)
			)
			(layer "F.Fab")
		)
		(pad "1" smd circle
			(at -0.40005 0 90)
			(size 0 0)
			(layers "F.Cu" "F.Mask" "F.Paste")
			(net "P12V_AUX")
		)
		(pad "2" smd circle
			(at 0.40005 0 90)
			(size 0 0)
			(layers "F.Cu" "F.Mask" "F.Paste")
			(net "P12V_E1S_0_EN_G")
		)
	)
	(footprint ""
		(layer "F.Cu")
		(at 109.22 -397.03248 90)
		(property "Reference" "R689"
			(at 0 0 90)
			(layer "F.SilkS")
			(hide yes)
			(effects
				(font
					(size 1.27 1.27)
				)
			)
		)
		(property "Value" ""
			(at 0 0 90)
			(layer "F.Fab")
			(effects
				(font
					(size 1.27 1.27)
				)
			)
		)
		(duplicate_pad_numbers_are_jumpers no)
		(fp_line
			(start 0.32512 -0.175006)
			(end 0.32512 0.175006)
			(stroke
				(width 0.1)
				(type default)
			)
			(layer "F.Fab")
		)
		(fp_line
			(start -0.32512 -0.175006)
			(end 0.32512 -0.175006)
			(stroke
				(width 0.1)
				(type default)
			)
			(layer "F.Fab")
		)
		(fp_line
			(start 0.32512 0.175006)
			(end -0.32512 0.175006)
			(stroke
				(width 0.1)
				(type default)
			)
			(layer "F.Fab")
		)
		(fp_line
			(start -0.32512 0.175006)
			(end -0.32512 -0.175006)
			(stroke
				(width 0.1)
				(type default)
			)
			(layer "F.Fab")
		)
		(pad "1" smd rect
			(at -0.2667 0 90)
			(size 0.3048 0.381)
			(layers "F.Cu" "F.Mask" "F.Paste")
			(net "SMB_RT_CPU1_P1_ROM_R_SCL")
		)
		(pad "2" smd rect
			(at 0.2667 0 270)
			(size 0.3048 0.381)
			(layers "F.Cu" "F.Mask" "F.Paste")
			(net "SMB_RT_CPU1_P1_ROM_SCL")
		)
	)
	(footprint ""
		(layer "F.Cu")
		(at 332.914498 -143.705834 180)
		(property "Reference" "PR8001"
			(at 0 0 180)
			(layer "F.SilkS")
			(hide yes)
			(effects
				(font
					(size 1.27 1.27)
				)
			)
		)
		(property "Value" ""
			(at 0 0 180)
			(layer "F.Fab")
			(effects
				(font
					(size 1.27 1.27)
				)
			)
		)
		(duplicate_pad_numbers_are_jumpers no)
		(fp_line
			(start 0.7874 0.4064)
			(end -0.7874 0.4064)
			(stroke
				(width 0.1524)
				(type default)
			)
			(layer "F.SilkS")
		)
		(fp_line
			(start 0.7874 -0.4064)
			(end 0.7874 0.4064)
			(stroke
				(width 0.1524)
				(type default)
			)
			(layer "F.SilkS")
		)
		(fp_line
			(start -0.7874 0.4064)
			(end -0.7874 -0.4064)
			(stroke
				(width 0.1524)
				(type default)
			)
			(layer "F.SilkS")
		)
		(fp_line
			(start -0.7874 -0.4064)
			(end 0.7874 -0.4064)
			(stroke
				(width 0.1524)
				(type default)
			)
			(layer "F.SilkS")
		)
		(fp_line
			(start 0.67945 0.3048)
			(end 0.120396 0.3048)
			(stroke
				(width 0.1)
				(type default)
			)
			(layer "F.Fab")
		)
		(fp_line
			(start 0.67945 -0.3048)
			(end 0.67945 0.3048)
			(stroke
				(width 0.1)
				(type default)
			)
			(layer "F.Fab")
		)
		(fp_line
			(start 0.12065 -0.2794)
			(end 0.12065 -0.3048)
			(stroke
				(width 0.1)
				(type default)
			)
			(layer "F.Fab")
		)
		(fp_line
			(start 0.12065 -0.3048)
			(end 0.67945 -0.3048)
			(stroke
				(width 0.1)
				(type default)
			)
			(layer "F.Fab")
		)
		(fp_line
			(start 0.120396 0.3048)
			(end 0.120396 0.2794)
			(stroke
				(width 0.1)
				(type default)
			)
			(layer "F.Fab")
		)
		(fp_line
			(start 0.120396 0.2794)
			(end -0.12065 0.2794)
			(stroke
				(width 0.1)
				(type default)
			)
			(layer "F.Fab")
		)
		(fp_line
			(start -0.12065 0.3048)
			(end -0.67945 0.3048)
			(stroke
				(width 0.1)
				(type default)
			)
			(layer "F.Fab")
		)
		(fp_line
			(start -0.12065 0.2794)
			(end -0.12065 0.3048)
			(stroke
				(width 0.1)
				(type default)
			)
			(layer "F.Fab")
		)
		(fp_line
			(start -0.12065 -0.2794)
			(end 0.12065 -0.2794)
			(stroke
				(width 0.1)
				(type default)
			)
			(layer "F.Fab")
		)
		(fp_line
			(start -0.12065 -0.305054)
			(end -0.12065 -0.2794)
			(stroke
				(width 0.1)
				(type default)
			)
			(layer "F.Fab")
		)
		(fp_line
			(start -0.67945 0.3048)
			(end -0.67945 -0.305054)
			(stroke
				(width 0.1)
				(type default)
			)
			(layer "F.Fab")
		)
		(fp_line
			(start -0.67945 -0.305054)
			(end -0.12065 -0.305054)
			(stroke
				(width 0.1)
				(type default)
			)
			(layer "F.Fab")
		)
		(pad "1" smd circle
			(at -0.40005 0 180)
			(size 0 0)
			(layers "F.Cu" "F.Mask" "F.Paste")
			(net "SW_PVDD18_S5_P0_BST")
		)
		(pad "2" smd circle
			(at 0.40005 0 180)
			(size 0 0)
			(layers "F.Cu" "F.Mask" "F.Paste")
			(net "SW_PVDD18_S5_P0_BST_R")
		)
	)
	(footprint ""
		(layer "F.Cu")
		(at 390.614662 -143.323056 -90)
		(property "Reference" "R6077"
			(at 0 0 270)
			(layer "F.SilkS")
			(hide yes)
			(effects
				(font
					(size 1.27 1.27)
				)
			)
		)
		(property "Value" ""
			(at 0 0 270)
			(layer "F.Fab")
			(effects
				(font
					(size 1.27 1.27)
				)
			)
		)
		(duplicate_pad_numbers_are_jumpers no)
		(fp_line
			(start -0.7874 0.4064)
			(end -0.7874 -0.4064)
			(stroke
				(width 0.1524)
				(type default)
			)
			(layer "F.SilkS")
		)
		(fp_line
			(start 0.7874 0.4064)
			(end -0.7874 0.4064)
			(stroke
				(width 0.1524)
				(type default)
			)
			(layer "F.SilkS")
		)
		(fp_line
			(start -0.7874 -0.4064)
			(end 0.7874 -0.4064)
			(stroke
				(width 0.1524)
				(type default)
			)
			(layer "F.SilkS")
		)
		(fp_line
			(start 0.7874 -0.4064)
			(end 0.7874 0.4064)
			(stroke
				(width 0.1524)
				(type default)
			)
			(layer "F.SilkS")
		)
		(fp_line
			(start -0.67945 0.3048)
			(end -0.67945 -0.305054)
			(stroke
				(width 0.1)
				(type default)
			)
			(layer "F.Fab")
		)
		(fp_line
			(start -0.12065 0.3048)
			(end -0.67945 0.3048)
			(stroke
				(width 0.1)
				(type default)
			)
			(layer "F.Fab")
		)
		(fp_line
			(start 0.120396 0.3048)
			(end 0.120396 0.2794)
			(stroke
				(width 0.1)
				(type default)
			)
			(layer "F.Fab")
		)
		(fp_line
			(start 0.67945 0.3048)
			(end 0.120396 0.3048)
			(stroke
				(width 0.1)
				(type default)
			)
			(layer "F.Fab")
		)
		(fp_line
			(start -0.12065 0.2794)
			(end -0.12065 0.3048)
			(stroke
				(width 0.1)
				(type default)
			)
			(layer "F.Fab")
		)
		(fp_line
			(start 0.120396 0.2794)
			(end -0.12065 0.2794)
			(stroke
				(width 0.1)
				(type default)
			)
			(layer "F.Fab")
		)
		(fp_line
			(start -0.12065 -0.2794)
			(end 0.12065 -0.2794)
			(stroke
				(width 0.1)
				(type default)
			)
			(layer "F.Fab")
		)
		(fp_line
			(start 0.12065 -0.2794)
			(end 0.12065 -0.3048)
			(stroke
				(width 0.1)
				(type default)
			)
			(layer "F.Fab")
		)
		(fp_line
			(start 0.12065 -0.3048)
			(end 0.67945 -0.3048)
			(stroke
				(width 0.1)
				(type default)
			)
			(layer "F.Fab")
		)
		(fp_line
			(start 0.67945 -0.3048)
			(end 0.67945 0.3048)
			(stroke
				(width 0.1)
				(type default)
			)
			(layer "F.Fab")
		)
		(fp_line
			(start -0.67945 -0.305054)
			(end -0.12065 -0.305054)
			(stroke
				(width 0.1)
				(type default)
			)
			(layer "F.Fab")
		)
		(fp_line
			(start -0.12065 -0.305054)
			(end -0.12065 -0.2794)
			(stroke
				(width 0.1)
				(type default)
			)
			(layer "F.Fab")
		)
		(pad "1" smd circle
			(at -0.40005 0 270)
			(size 0 0)
			(layers "F.Cu" "F.Mask" "F.Paste")
			(net "SMB_SCM_2_R3_SDA")
		)
		(pad "2" smd circle
			(at 0.40005 0 270)
			(size 0 0)
			(layers "F.Cu" "F.Mask" "F.Paste")
			(net "SMB_SCM_2_R4_SDA")
		)
	)
)
